#ISCELL
  logical_power design_note *
  *
#ISCELL
  mstr_misc dns *
  *
#ISCELL
  pure_quanta quanta_title_block_c *
  *
#ISCELL
  standard offpage *
  page190_i10
#CELL
  pure_quanta q_res *
  page190_i100
#CELL
  pure_quanta q_res *
  page190_i101
#CELL
  pure_quanta q_res *
  page190_i102
#ISCELL
  standard offpage *
  page190_i103
#CELL
  pure_quanta q_res *
  page190_i105
#ISCELL
  standard offpage *
  page190_i11
#ISCELL
  standard offpage *
  page190_i12
#ISCELL
  standard offpage *
  page190_i14
#ISCELL
  standard offpage *
  page190_i15
#ISCELL
  standard offpage *
  page190_i18
#ISCELL
  logical_power universal_gnd *
  page190_i20
#ISCELL
  logical_power universal_gnd *
  page190_i21
#ISCELL
  logical_power universal_power *
  page190_i24
#ISCELL
  standard offpage *
  page190_i32
#CELL
  pure_quanta q_res *
  page190_i33
#CELL
  pure_quanta nc7sb3157 *
  page190_i34
#CELL
  pure_quanta q_cap *
  page190_i36
#CELL
  pure_quanta q_cap *
  page190_i37
#CELL
  pure_quanta q_res *
  page190_i38
#CELL
  pure_quanta nc7sb3157 *
  page190_i39
#ISCELL
  logical_power universal_gnd *
  page190_i40
#ISCELL
  standard offpage *
  page190_i41
#CELL
  pure_quanta q_cap *
  page190_i43
#ISCELL
  logical_power universal_power *
  page190_i44
#CELL
  pure_quanta q_cap *
  page190_i45
#ISCELL
  logical_power universal_gnd *
  page190_i46
#ISCELL
  standard offpage *
  page190_i48
#ISCELL
  standard offpage *
  page190_i5
#ISCELL
  standard offpage *
  page190_i50
#ISCELL
  standard offpage *
  page190_i51
#ISCELL
  standard offpage *
  page190_i53
#CELL
  pure_quanta q_res *
  page190_i54
#ISCELL
  standard offpage *
  page190_i6
#ISCELL
  standard offpage *
  page190_i7
#CELL
  pure_quanta q_res *
  page190_i70
#ISCELL
  logical_power universal_power *
  page190_i71
#ISCELL
  standard offpage *
  page190_i79
#ISCELL
  standard offpage *
  page190_i8
#ISCELL
  standard offpage *
  page190_i81
#ISCELL
  standard offpage *
  page190_i82
#ISCELL
  logical_power universal_gnd *
  page190_i83
#CELL
  pure_quanta q_cap *
  page190_i84
#ISCELL
  logical_power universal_gnd *
  page190_i85
#ISCELL
  logical_power universal_power *
  page190_i86
#CELL
  pure_quanta q_res *
  page190_i87
#ISCELL
  logical_power universal_power *
  page190_i88
#CELL
  pure_quanta q_res *
  page190_i89
#ISCELL
  standard offpage *
  page190_i9
#ISCELL
  logical_power universal_gnd *
  page190_i90
#CELL
  pure_quanta q_res *
  page190_i91
#ISCELL
  standard offpage *
  page190_i92
#ISCELL
  logical_power universal_power *
  page190_i93
#CELL
  pure_quanta q_res *
  page190_i94
#CELL
  pure_quanta 74lvc1g07se7 *
  page190_i95
#CELL
  pure_quanta q_res *
  page190_i96
#CELL
  pure_quanta q_res *
  page190_i97
#CELL
  pure_quanta q_res *
  page190_i98
#CELL
  pure_quanta q_res *
  page190_i99
